(kicad_pcb
	(version 20241229)
	(generator "pcbnew")
	(generator_version "9.0")
	(general
		(thickness 1.294)
		(legacy_teardrops no)
	)
	(paper "A3")
	(title_block
		(title "Kintex 410T devboard")
		(date "2024-04-03")
		(rev "1.1.2")
		(comment 9 "footprints 218-222 of 975")
	)
	(layers
		(0 "F.Cu" mixed)
		(4 "In1.Cu" power)
		(6 "In2.Cu" power)
		(8 "In3.Cu" mixed)
		(10 "In4.Cu" power)
		(12 "In5.Cu" mixed)
		(14 "In6.Cu" power)
		(16 "In7.Cu" mixed)
		(18 "In8.Cu" power)
		(2 "B.Cu" mixed)
		(9 "F.Adhes" user "F.Adhesive")
		(11 "B.Adhes" user "B.Adhesive")
		(13 "F.Paste" user)
		(15 "B.Paste" user)
		(5 "F.SilkS" user "F.Silkscreen")
		(7 "B.SilkS" user "B.Silkscreen")
		(1 "F.Mask" user)
		(3 "B.Mask" user)
		(17 "Dwgs.User" user "User.Drawings")
		(19 "Cmts.User" user "User.Comments")
		(21 "Eco1.User" user "User.Eco1")
		(23 "Eco2.User" user "User.Eco2")
		(25 "Edge.Cuts" user)
		(27 "Margin" user)
		(31 "F.CrtYd" user "F.Courtyard")
		(29 "B.CrtYd" user "B.Courtyard")
		(35 "F.Fab" user)
		(33 "B.Fab" user)
	)
	(footprint "antmicro-footprints:C_0805_2012Metric"
		(layer "F.Cu")
		(at 191.5 161.949 -90)
		(descr "Capacitor SMD 0805")
		(tags "capacitor SMD 0805")
		(property "Reference" "C345"
			(at -1.399 3.15 90)
			(layer "F.SilkS")
			(effects
				(font
					(size 0.7 0.7)
					(thickness 0.15)
				)
				(justify right bottom)
			)
		)
		(property "Value" "C_22u_25V_0805"
			(at 0 1.947 90)
			(layer "F.Fab")
			(effects
				(font
					(size 0.7 0.7)
					(thickness 0.15)
				)
				(justify right bottom)
			)
		)
		(property "Description" "SMT Multilayer Ceramic Capacitor, 22uF, +/-20%, 25V, X5R, 0805 [2012 Metric]"
			(at 0 0 270)
			(layer "F.Fab")
			(hide yes)
			(effects
				(font
					(size 1.27 1.27)
					(thickness 0.15)
				)
			)
		)
		(property "Author" "Antmicro"
			(at 29.551 353.449 0)
			(layer "F.Fab")
			(hide yes)
			(effects
				(font
					(size 1 1)
					(thickness 0.15)
				)
			)
		)
		(property "Dielectric" "X5R"
			(at 29.551 353.449 0)
			(layer "F.Fab")
			(hide yes)
			(effects
				(font
					(size 1 1)
					(thickness 0.15)
				)
			)
		)
		(property "License" "Apache-2.0"
			(at 29.551 353.449 0)
			(layer "F.Fab")
			(hide yes)
			(effects
				(font
					(size 1 1)
					(thickness 0.15)
				)
			)
		)
		(property "MPN" "CL21A226MAYNNNE"
			(at 29.551 353.449 0)
			(layer "F.Fab")
			(hide yes)
			(effects
				(font
					(size 1 1)
					(thickness 0.15)
				)
			)
		)
		(property "Manufacturer" "Samsung Electro-Mechanics"
			(at 29.551 353.449 0)
			(layer "F.Fab")
			(hide yes)
			(effects
				(font
					(size 1 1)
					(thickness 0.15)
				)
			)
		)
		(property "Val" "22u"
			(at 29.551 353.449 0)
			(layer "F.Fab")
			(hide yes)
			(effects
				(font
					(size 1 1)
					(thickness 0.15)
				)
			)
		)
		(property "Voltage" "25V"
			(at 29.551 353.449 0)
			(layer "F.Fab")
			(hide yes)
			(effects
				(font
					(size 1 1)
					(thickness 0.15)
				)
			)
		)
		(sheetname "DC-DC Converters")
		(sheetfile "dc-dc.kicad_sch")
		(attr smd)
		(fp_line
			(start -0.3 0.7)
			(end 0.3 0.7)
			(stroke
				(width 0.15)
				(type solid)
			)
			(layer "F.SilkS")
		)
		(fp_line
			(start -0.3 -0.7)
			(end 0.3 -0.7)
			(stroke
				(width 0.15)
				(type solid)
			)
			(layer "F.SilkS")
		)
		(fp_rect
			(start 1.95 -0.9)
			(end -1.95 0.9)
			(stroke
				(width 0.05)
				(type default)
			)
			(fill no)
			(layer "F.CrtYd")
		)
		(fp_rect
			(start -0.95 -0.675)
			(end 0.95 0.675)
			(stroke
				(width 0.15)
				(type solid)
			)
			(fill no)
			(layer "F.Fab")
		)
		(pad "1" smd roundrect
			(at -1.1 0 270)
			(size 1.2 1.3)
			(layers "F.Cu" "F.Mask" "F.Paste")
			(roundrect_rratio 0.25)
			(net 1 "GND")
			(pintype "passive")
		)
		(pad "2" smd roundrect
			(at 1.1 0 270)
			(size 1.2 1.3)
			(layers "F.Cu" "F.Mask" "F.Paste")
			(roundrect_rratio 0.25)
			(net 702 "VDC")
			(pintype "passive")
		)
	)
	(footprint "antmicro-footprints:C_0402_1005Metric"
		(layer "F.Cu")
		(at 173.570001 118.510001 180)
		(descr "Capacitor SMD 0402")
		(tags "capacitor SMD 0402")
		(property "Reference" "C305"
			(at -3.729999 -0.342499 0)
			(layer "F.SilkS")
			(effects
				(font
					(size 0.7 0.7)
					(thickness 0.15)
				)
				(justify right bottom)
			)
		)
		(property "Value" "C_100n_0402"
			(at 0 1.4 0)
			(layer "F.Fab")
			(effects
				(font
					(size 0.7 0.7)
					(thickness 0.15)
				)
				(justify right bottom)
			)
		)
		(property "Description" "SMD Multilayer Ceramic Capacitor, 0.1 µF, 50 V, 0402 [1005 Metric], ± 10%, X5R, GRM Series"
			(at 0 0 180)
			(layer "F.Fab")
			(hide yes)
			(effects
				(font
					(size 1.27 1.27)
					(thickness 0.15)
				)
			)
		)
		(property "Author" "Antmicro"
			(at 347.140002 237.020002 0)
			(layer "F.Fab")
			(hide yes)
			(effects
				(font
					(size 1 1)
					(thickness 0.15)
				)
			)
		)
		(property "Dielectric" "X5R"
			(at 347.140002 237.020002 0)
			(layer "F.Fab")
			(hide yes)
			(effects
				(font
					(size 1 1)
					(thickness 0.15)
				)
			)
		)
		(property "License" "Apache-2.0"
			(at 347.140002 237.020002 0)
			(layer "F.Fab")
			(hide yes)
			(effects
				(font
					(size 1 1)
					(thickness 0.15)
				)
			)
		)
		(property "MPN" "GRM155R61H104KE14D"
			(at 347.140002 237.020002 0)
			(layer "F.Fab")
			(hide yes)
			(effects
				(font
					(size 1 1)
					(thickness 0.15)
				)
			)
		)
		(property "Manufacturer" "Murata"
			(at 347.140002 237.020002 0)
			(layer "F.Fab")
			(hide yes)
			(effects
				(font
					(size 1 1)
					(thickness 0.15)
				)
			)
		)
		(property "Val" "100n"
			(at 347.140002 237.020002 0)
			(layer "F.Fab")
			(hide yes)
			(effects
				(font
					(size 1 1)
					(thickness 0.15)
				)
			)
		)
		(property "Voltage" "50V"
			(at 347.140002 237.020002 0)
			(layer "F.Fab")
			(hide yes)
			(effects
				(font
					(size 1 1)
					(thickness 0.15)
				)
			)
		)
		(sheetname "FMC+ HSPC")
		(sheetfile "fmc-hspc.kicad_sch")
		(attr smd)
		(fp_rect
			(start -0.925 -0.47)
			(end 0.925 0.47)
			(stroke
				(width 0.05)
				(type default)
			)
			(fill no)
			(layer "F.CrtYd")
		)
		(fp_line
			(start 0.504 0.248)
			(end -0.494 0.248)
			(stroke
				(width 0.15)
				(type solid)
			)
			(layer "F.Fab")
		)
		(fp_line
			(start 0.504 -0.25)
			(end 0.504 0.248)
			(stroke
				(width 0.15)
				(type solid)
			)
			(layer "F.Fab")
		)
		(fp_line
			(start -0.494 0.248)
			(end -0.494 -0.25)
			(stroke
				(width 0.15)
				(type solid)
			)
			(layer "F.Fab")
		)
		(fp_line
			(start -0.494 -0.25)
			(end 0.504 -0.25)
			(stroke
				(width 0.15)
				(type solid)
			)
			(layer "F.Fab")
		)
		(pad "1" smd roundrect
			(at -0.48 0 180)
			(size 0.59 0.64)
			(layers "F.Cu" "F.Mask" "F.Paste")
			(roundrect_rratio 0.25)
			(net 82 "/FMC+ HSPC/GTX116.TX0_N")
			(pintype "passive")
		)
		(pad "2" smd roundrect
			(at 0.48 0 180)
			(size 0.59 0.64)
			(layers "F.Cu" "F.Mask" "F.Paste")
			(roundrect_rratio 0.25)
			(net 81 "/FMC+ HSPC/GTX_TX3_C_N")
			(pintype "passive")
		)
	)
	(footprint "antmicro-footprints:R_0402_1005Metric"
		(layer "F.Cu")
		(at 194.1 167.149 180)
		(descr "Resistor SMD 0402")
		(tags "resistor SMD 0402")
		(property "Reference" "R332"
			(at -0.375 -4.101 180)
			(layer "F.SilkS")
			(effects
				(font
					(size 0.7 0.7)
					(thickness 0.15)
				)
				(justify left bottom)
			)
		)
		(property "Value" "R_205k_0402"
			(at 0 1.4 180)
			(layer "F.Fab")
			(effects
				(font
					(size 0.7 0.7)
					(thickness 0.15)
				)
				(justify left bottom)
			)
		)
		(property "Description" "SMD Chip Resistor"
			(at 0 0 180)
			(layer "F.Fab")
			(hide yes)
			(effects
				(font
					(size 1.27 1.27)
					(thickness 0.15)
				)
			)
		)
		(property "Author" "Antmicro"
			(at 388.2 334.298 0)
			(layer "F.Fab")
			(hide yes)
			(effects
				(font
					(size 1 1)
					(thickness 0.15)
				)
			)
		)
		(property "License" "Apache-2.0"
			(at 388.2 334.298 0)
			(layer "F.Fab")
			(hide yes)
			(effects
				(font
					(size 1 1)
					(thickness 0.15)
				)
			)
		)
		(property "MPN" "CR0402-FX-2053GLF"
			(at 388.2 334.298 0)
			(layer "F.Fab")
			(hide yes)
			(effects
				(font
					(size 1 1)
					(thickness 0.15)
				)
			)
		)
		(property "Manufacturer" "Bourns"
			(at 388.2 334.298 0)
			(layer "F.Fab")
			(hide yes)
			(effects
				(font
					(size 1 1)
					(thickness 0.15)
				)
			)
		)
		(property "Tolerance" "1%"
			(at 388.2 334.298 0)
			(layer "F.Fab")
			(hide yes)
			(effects
				(font
					(size 1 1)
					(thickness 0.15)
				)
			)
		)
		(property "Val" "205k"
			(at 388.2 334.298 0)
			(layer "F.Fab")
			(hide yes)
			(effects
				(font
					(size 1 1)
					(thickness 0.15)
				)
			)
		)
		(sheetname "DC-DC Converters")
		(sheetfile "dc-dc.kicad_sch")
		(attr smd)
		(fp_rect
			(start -0.925 -0.47)
			(end 0.925 0.47)
			(stroke
				(width 0.05)
				(type default)
			)
			(fill no)
			(layer "F.CrtYd")
		)
		(fp_rect
			(start -0.5 -0.25)
			(end 0.5 0.25)
			(stroke
				(width 0.15)
				(type solid)
			)
			(fill no)
			(layer "F.Fab")
		)
		(pad "1" smd roundrect
			(at -0.48 0 180)
			(size 0.59 0.64)
			(layers "F.Cu" "F.Mask" "F.Paste")
			(roundrect_rratio 0.25)
			(net 1 "GND")
			(pintype "passive")
		)
		(pad "2" smd roundrect
			(at 0.48 0 180)
			(size 0.59 0.64)
			(layers "F.Cu" "F.Mask" "F.Paste")
			(roundrect_rratio 0.25)
			(net 1230 "Net-(C364-Pad1)")
			(pintype "passive")
		)
	)
	(footprint "antmicro-footprints:DFN-10-1EP_3x3mm"
		(layer "F.Cu")
		(at 155.175 154.7 180)
		(property "Reference" "U39"
			(at -2.175 1.9 180)
			(layer "F.SilkS")
			(effects
				(font
					(size 0.7 0.7)
					(thickness 0.15)
				)
				(justify right bottom)
			)
		)
		(property "Value" "NCP51400MNTXG"
			(at 0 2.8 0)
			(layer "F.Fab")
			(effects
				(font
					(size 0.7 0.7)
					(thickness 0.15)
				)
				(justify right bottom)
			)
		)
		(property "Description" "Fixed LDO Voltage Regulator, 2.375V to 5.5V, 1.2 V Drop, 750 mV/3A out, DFN-10 Pins"
			(at 0 0 180)
			(layer "F.Fab")
			(hide yes)
			(effects
				(font
					(size 1.27 1.27)
					(thickness 0.15)
				)
			)
		)
		(property "Author" "Antmicro"
			(at 310.35 309.4 0)
			(layer "F.Fab")
			(hide yes)
			(effects
				(font
					(size 1 1)
					(thickness 0.15)
				)
			)
		)
		(property "License" "Apache-2.0"
			(at 310.35 309.4 0)
			(layer "F.Fab")
			(hide yes)
			(effects
				(font
					(size 1 1)
					(thickness 0.15)
				)
			)
		)
		(property "MPN" "NCP51400MNTXG"
			(at 310.35 309.4 0)
			(layer "F.Fab")
			(hide yes)
			(effects
				(font
					(size 1 1)
					(thickness 0.15)
				)
			)
		)
		(property "Manufacturer" "ON Semiconductor"
			(at 310.35 309.4 0)
			(layer "F.Fab")
			(hide yes)
			(effects
				(font
					(size 1 1)
					(thickness 0.15)
				)
			)
		)
		(sheetname "DC-DC Converters")
		(sheetfile "dc-dc.kicad_sch")
		(attr smd)
		(fp_line
			(start 1.601 1.6)
			(end 1.601 1.35)
			(stroke
				(width 0.15)
				(type solid)
			)
			(layer "F.SilkS")
		)
		(fp_line
			(start 1.601 1.6)
			(end 1.401 1.6)
			(stroke
				(width 0.15)
				(type solid)
			)
			(layer "F.SilkS")
		)
		(fp_line
			(start 1.601 -1.601)
			(end 1.601 -1.401)
			(stroke
				(width 0.15)
				(type solid)
			)
			(layer "F.SilkS")
		)
		(fp_line
			(start 1.601 -1.601)
			(end 1.351 -1.601)
			(stroke
				(width 0.15)
				(type solid)
			)
			(layer "F.SilkS")
		)
		(fp_line
			(start -1.249 -1.601)
			(end -0.824 -1.601)
			(stroke
				(width 0.15)
				(type solid)
			)
			(layer "F.SilkS")
		)
		(fp_line
			(start -1.249 -1.601)
			(end -1.624 -1.226)
			(stroke
				(width 0.15)
				(type solid)
			)
			(layer "F.SilkS")
		)
		(fp_line
			(start -1.6 1.6)
			(end -1.35 1.6)
			(stroke
				(width 0.15)
				(type solid)
			)
			(layer "F.SilkS")
		)
		(fp_line
			(start -1.6 1.6)
			(end -1.6 1.35)
			(stroke
				(width 0.15)
				(type solid)
			)
			(layer "F.SilkS")
		)
		(fp_line
			(start -1.624 -1.226)
			(end -1.773 -1.226)
			(stroke
				(width 0.15)
				(type solid)
			)
			(layer "F.SilkS")
		)
		(fp_circle
			(center -1.8 -1.6)
			(end -1.8 -1.551)
			(stroke
				(width 0.15)
				(type solid)
			)
			(fill yes)
			(layer "F.SilkS")
		)
		(fp_line
			(start 1.89 1.75)
			(end 1.89 -1.73)
			(stroke
				(width 0.05)
				(type solid)
			)
			(layer "F.CrtYd")
		)
		(fp_line
			(start 1.89 1.75)
			(end -1.91 1.75)
			(stroke
				(width 0.05)
				(type solid)
			)
			(layer "F.CrtYd")
		)
		(fp_line
			(start -1.91 1.75)
			(end -1.91 -1.73)
			(stroke
				(width 0.05)
				(type solid)
			)
			(layer "F.CrtYd")
		)
		(fp_line
			(start -1.91 -1.73)
			(end 1.89 -1.73)
			(stroke
				(width 0.05)
				(type solid)
			)
			(layer "F.CrtYd")
		)
		(fp_line
			(start 1.5 1.499)
			(end -1.499 1.499)
			(stroke
				(width 0.15)
				(type solid)
			)
			(layer "F.Fab")
		)
		(fp_line
			(start 1.5 -1.5)
			(end 1.5 1.499)
			(stroke
				(width 0.15)
				(type solid)
			)
			(layer "F.Fab")
		)
		(fp_line
			(start 1.5 -1.5)
			(end -1.175 -1.5)
			(stroke
				(width 0.15)
				(type solid)
			)
			(layer "F.Fab")
		)
		(fp_line
			(start -1.499 1.499)
			(end -1.499 -1.176)
			(stroke
				(width 0.15)
				(type solid)
			)
			(layer "F.Fab")
		)
		(fp_line
			(start -1.499 -1.18)
			(end -1.179 -1.5)
			(stroke
				(width 0.15)
				(type solid)
			)
			(layer "F.Fab")
		)
		(pad "1" smd roundrect
			(at -1.425 -1 90)
			(size 0.25 0.7)
			(layers "F.Cu" "F.Mask" "F.Paste")
			(roundrect_rratio 0.25)
			(net 744 "/DC-DC Converters/VDDR_VRI")
			(pinfunction "VRI")
			(pintype "unspecified")
		)
		(pad "2" smd roundrect
			(at -1.425 -0.5 90)
			(size 0.25 0.7)
			(layers "F.Cu" "F.Mask" "F.Paste")
			(roundrect_rratio 0.25)
			(net 25 "+1V35")
			(pinfunction "PVCC")
			(pintype "unspecified")
		)
		(pad "3" smd roundrect
			(at -1.425 0 90)
			(size 0.25 0.7)
			(layers "F.Cu" "F.Mask" "F.Paste")
			(roundrect_rratio 0.25)
			(net 750 "/DC-DC Converters/VDDR_VTT")
			(pinfunction "VTT")
			(pintype "unspecified")
		)
		(pad "4" smd roundrect
			(at -1.425 0.498 90)
			(size 0.25 0.7)
			(layers "F.Cu" "F.Mask" "F.Paste")
			(roundrect_rratio 0.25)
			(net 1 "GND")
			(pinfunction "PGND")
			(pintype "power_in")
		)
		(pad "5" smd roundrect
			(at -1.425 0.998 90)
			(size 0.25 0.7)
			(layers "F.Cu" "F.Mask" "F.Paste")
			(roundrect_rratio 0.25)
			(net 750 "/DC-DC Converters/VDDR_VTT")
			(pinfunction "VTTS")
			(pintype "unspecified")
		)
		(pad "6" smd roundrect
			(at 1.426 0.998 90)
			(size 0.25 0.7)
			(layers "F.Cu" "F.Mask" "F.Paste")
			(roundrect_rratio 0.25)
			(net 11 "+0V675_VREF")
			(pinfunction "VRO")
			(pintype "unspecified")
		)
		(pad "7" smd roundrect
			(at 1.426 0.498 90)
			(size 0.25 0.7)
			(layers "F.Cu" "F.Mask" "F.Paste")
			(roundrect_rratio 0.25)
			(net 1191 "/DC-DC Converters/+0V675_EN")
			(pinfunction "EN")
			(pintype "unspecified")
		)
		(pad "8" smd roundrect
			(at 1.426 0 90)
			(size 0.25 0.7)
			(layers "F.Cu" "F.Mask" "F.Paste")
			(roundrect_rratio 0.25)
			(net 1 "GND")
			(pinfunction "GND")
			(pintype "power_in")
		)
		(pad "9" smd roundrect
			(at 1.426 -0.5 90)
			(size 0.25 0.7)
			(layers "F.Cu" "F.Mask" "F.Paste")
			(roundrect_rratio 0.25)
			(net 1055 "/DC-DC Converters/VDDR_PGOOD")
			(pinfunction "PGOOD")
			(pintype "power_in")
		)
		(pad "10" smd roundrect
			(at 1.426 -1 90)
			(size 0.25 0.7)
			(layers "F.Cu" "F.Mask" "F.Paste")
			(roundrect_rratio 0.25)
			(net 24 "+3V3")
			(pinfunction "VCC")
			(pintype "power_in")
		)
		(pad "11" smd roundrect
			(at 0 0 90)
			(size 2.38 1.65)
			(layers "F.Cu" "F.Mask" "F.Paste")
			(roundrect_rratio 0.05)
			(net 1 "GND")
			(pinfunction "EPAD")
			(pintype "unspecified")
		)
	)
	(footprint "antmicro-footprints:C_0402_1005Metric"
		(layer "F.Cu")
		(at 252.999 101)
		(descr "Capacitor SMD 0402")
		(tags "capacitor SMD 0402")
		(property "Reference" "C394"
			(at -1.349 1.25 0)
			(layer "F.SilkS")
			(effects
				(font
					(size 0.7 0.7)
					(thickness 0.15)
				)
				(justify left bottom)
			)
		)
		(property "Value" "C_100n_0402"
			(at 0 1.169 0)
			(layer "F.Fab")
			(effects
				(font
					(size 0.7 0.7)
					(thickness 0.15)
				)
				(justify left bottom)
			)
		)
		(property "Description" "SMD Multilayer Ceramic Capacitor, 0.1 µF, 50 V, 0402 [1005 Metric], ± 10%, X5R, GRM Series"
			(at 0 0 0)
			(layer "F.Fab")
			(hide yes)
			(effects
				(font
					(size 1.27 1.27)
					(thickness 0.15)
				)
			)
		)
		(property "Author" "Antmicro"
			(at 0 0 0)
			(layer "F.Fab")
			(hide yes)
			(effects
				(font
					(size 1 1)
					(thickness 0.15)
				)
			)
		)
		(property "Dielectric" "X5R"
			(at 0 0 0)
			(layer "F.Fab")
			(hide yes)
			(effects
				(font
					(size 1 1)
					(thickness 0.15)
				)
			)
		)
		(property "License" "Apache-2.0"
			(at 0 0 0)
			(layer "F.Fab")
			(hide yes)
			(effects
				(font
					(size 1 1)
					(thickness 0.15)
				)
			)
		)
		(property "MPN" "GRM155R61H104KE14D"
			(at 0 0 0)
			(layer "F.Fab")
			(hide yes)
			(effects
				(font
					(size 1 1)
					(thickness 0.15)
				)
			)
		)
		(property "Manufacturer" "Murata"
			(at 0 0 0)
			(layer "F.Fab")
			(hide yes)
			(effects
				(font
					(size 1 1)
					(thickness 0.15)
				)
			)
		)
		(property "Val" "100n"
			(at 0 0 0)
			(layer "F.Fab")
			(hide yes)
			(effects
				(font
					(size 1 1)
					(thickness 0.15)
				)
			)
		)
		(property "Voltage" "50V"
			(at 0 0 0)
			(layer "F.Fab")
			(hide yes)
			(effects
				(font
					(size 1 1)
					(thickness 0.15)
				)
			)
		)
		(sheetname "USB PHY")
		(sheetfile "usb-phy.kicad_sch")
		(attr smd)
		(fp_rect
			(start -0.925 -0.47)
			(end 0.925 0.47)
			(stroke
				(width 0.05)
				(type default)
			)
			(fill no)
			(layer "F.CrtYd")
		)
		(fp_line
			(start -0.494 -0.25)
			(end 0.504 -0.25)
			(stroke
				(width 0.15)
				(type solid)
			)
			(layer "F.Fab")
		)
		(fp_line
			(start -0.494 0.248)
			(end -0.494 -0.25)
			(stroke
				(width 0.15)
				(type solid)
			)
			(layer "F.Fab")
		)
		(fp_line
			(start 0.504 -0.25)
			(end 0.504 0.248)
			(stroke
				(width 0.15)
				(type solid)
			)
			(layer "F.Fab")
		)
		(fp_line
			(start 0.504 0.248)
			(end -0.494 0.248)
			(stroke
				(width 0.15)
				(type solid)
			)
			(layer "F.Fab")
		)
		(pad "1" smd roundrect
			(at -0.48 0)
			(size 0.59 0.64)
			(layers "F.Cu" "F.Mask" "F.Paste")
			(roundrect_rratio 0.25)
			(net 1 "GND")
			(pintype "passive")
		)
		(pad "2" smd roundrect
			(at 0.48 0)
			(size 0.59 0.64)
			(layers "F.Cu" "F.Mask" "F.Paste")
			(roundrect_rratio 0.25)
			(net 705 "/USB PHY/USB_HOST_VBUS")
			(pintype "passive")
		)
	)
)
